(kicad_pcb
	(version 20240108)
	(generator "pcbnew")
	(generator_version "8.0")
	(general
		(thickness 1.6)
		(legacy_teardrops no)
	)
	(paper "A4")
	(title_block
		(title "Jetson Orin Baseboard OCuLink Expansion")
		(date "2025-03-18")
		(rev "1.1.0")
		(company "Antmicro Ltd")
		(comment 1 "www.antmicro.com")
		(comment 9 "footprints 113-117 of 119")
	)
	(layers
		(0 "F.Cu" signal)
		(1 "In1.Cu" signal)
		(2 "In2.Cu" signal)
		(31 "B.Cu" signal)
		(32 "B.Adhes" user "B.Adhesive")
		(33 "F.Adhes" user "F.Adhesive")
		(34 "B.Paste" user)
		(35 "F.Paste" user)
		(36 "B.SilkS" user "B.Silkscreen")
		(37 "F.SilkS" user "F.Silkscreen")
		(38 "B.Mask" user)
		(39 "F.Mask" user)
		(40 "Dwgs.User" user "User.Drawings")
		(41 "Cmts.User" user "User.Comments")
		(42 "Eco1.User" user "User.Eco1")
		(43 "Eco2.User" user "User.Eco2")
		(44 "Edge.Cuts" user)
		(45 "Margin" user)
		(46 "B.CrtYd" user "B.Courtyard")
		(47 "F.CrtYd" user "F.Courtyard")
		(48 "B.Fab" user)
		(49 "F.Fab" user)
	)
	(footprint "antmicro-footprints:C_0402_1005Metric"
		(layer "B.Cu")
		(at 121.275 127.913 -90)
		(descr "Capacitor SMD 0402")
		(tags "capacitor SMD 0402")
		(property "Reference" "C21"
			(at 1.627 -0.465 90)
			(layer "B.SilkS")
			(effects
				(font
					(size 0.7 0.7)
					(thickness 0.15)
				)
				(justify left bottom mirror)
			)
		)
		(property "Value" "C_100n_0402"
			(at -1.022927 -2.155213 90)
			(layer "B.Fab")
			(effects
				(font
					(size 0.7 0.7)
					(thickness 0.15)
				)
				(justify left bottom mirror)
			)
		)
		(property "Footprint" "antmicro-footprints:C_0402_1005Metric"
			(at 0 0 90)
			(layer "B.Fab")
			(hide yes)
			(effects
				(font
					(size 1.27 1.27)
					(thickness 0.15)
				)
				(justify mirror)
			)
		)
		(property "Datasheet" "https://www.murata.com/products/productdetail?partno=GRM155R61H104KE14%23"
			(at 0 0 90)
			(layer "B.Fab")
			(hide yes)
			(effects
				(font
					(size 1.27 1.27)
					(thickness 0.15)
				)
				(justify mirror)
			)
		)
		(property "Description" "SMD Multilayer Ceramic Capacitor, 0.1 µF, 50 V, 0402 [1005 Metric], ± 10%, X5R, GRM Series"
			(at 0 0 90)
			(layer "B.Fab")
			(hide yes)
			(effects
				(font
					(size 1.27 1.27)
					(thickness 0.15)
				)
				(justify mirror)
			)
		)
		(property "MPN" "GRM155R61H104KE14D"
			(at 0 0 90)
			(unlocked yes)
			(layer "B.Fab")
			(hide yes)
			(effects
				(font
					(size 1 1)
					(thickness 0.15)
				)
				(justify mirror)
			)
		)
		(property "Manufacturer" "Murata"
			(at 0 0 90)
			(unlocked yes)
			(layer "B.Fab")
			(hide yes)
			(effects
				(font
					(size 1 1)
					(thickness 0.15)
				)
				(justify mirror)
			)
		)
		(property "License" "Apache-2.0"
			(at 0 0 90)
			(unlocked yes)
			(layer "B.Fab")
			(hide yes)
			(effects
				(font
					(size 1 1)
					(thickness 0.15)
				)
				(justify mirror)
			)
		)
		(property "Author" "Antmicro"
			(at 0 0 90)
			(unlocked yes)
			(layer "B.Fab")
			(hide yes)
			(effects
				(font
					(size 1 1)
					(thickness 0.15)
				)
				(justify mirror)
			)
		)
		(property "Val" "100n"
			(at 0 0 90)
			(unlocked yes)
			(layer "B.Fab")
			(hide yes)
			(effects
				(font
					(size 1 1)
					(thickness 0.15)
				)
				(justify mirror)
			)
		)
		(property "Voltage" "50V"
			(at 0 0 90)
			(unlocked yes)
			(layer "B.Fab")
			(hide yes)
			(effects
				(font
					(size 1 1)
					(thickness 0.15)
				)
				(justify mirror)
			)
		)
		(property "Dielectric" "X5R"
			(at 0 0 90)
			(unlocked yes)
			(layer "B.Fab")
			(hide yes)
			(effects
				(font
					(size 1 1)
					(thickness 0.15)
				)
				(justify mirror)
			)
		)
		(property "Public" "False"
			(at 0 0 90)
			(unlocked yes)
			(layer "B.Fab")
			(hide yes)
			(effects
				(font
					(size 1 1)
					(thickness 0.15)
				)
				(justify mirror)
			)
		)
		(sheetname "Root")
		(sheetfile "jetson-orin-baseboard-oculink-expansion.kicad_sch")
		(attr smd)
		(fp_rect
			(start -0.925 0.47)
			(end 0.925 -0.47)
			(stroke
				(width 0.05)
				(type default)
			)
			(fill none)
			(layer "B.CrtYd")
		)
		(fp_line
			(start -0.494 0.25)
			(end -0.494 -0.248)
			(stroke
				(width 0.15)
				(type solid)
			)
			(layer "B.Fab")
		)
		(fp_line
			(start 0.504 0.25)
			(end -0.494 0.25)
			(stroke
				(width 0.15)
				(type solid)
			)
			(layer "B.Fab")
		)
		(fp_line
			(start -0.494 -0.248)
			(end 0.504 -0.248)
			(stroke
				(width 0.15)
				(type solid)
			)
			(layer "B.Fab")
		)
		(fp_line
			(start 0.504 -0.248)
			(end 0.504 0.25)
			(stroke
				(width 0.15)
				(type solid)
			)
			(layer "B.Fab")
		)
		(fp_text user "License: Apache-2.0"
			(at -0.939 -5.799 90)
			(layer "B.Fab")
			(hide yes)
			(effects
				(font
					(size 0.7 0.7)
					(thickness 0.15)
				)
				(justify left bottom mirror)
			)
		)
		(fp_text user "${REFERENCE}"
			(at -0.939 -4.599 90)
			(layer "B.Fab")
			(hide yes)
			(effects
				(font
					(size 0.7 0.7)
					(thickness 0.15)
				)
				(justify left bottom mirror)
			)
		)
		(fp_text user "Author: Antmicro"
			(at -0.939 -3.399 90)
			(layer "B.Fab")
			(hide yes)
			(effects
				(font
					(size 0.7 0.7)
					(thickness 0.15)
				)
				(justify left bottom mirror)
			)
		)
		(pad "1" smd roundrect
			(at -0.48 0 270)
			(size 0.59 0.64)
			(layers "B.Cu" "B.Paste" "B.Mask")
			(roundrect_rratio 0.25)
			(net 51 "GND")
			(pintype "passive")
		)
		(pad "2" smd roundrect
			(at 0.48 0 270)
			(size 0.59 0.64)
			(layers "B.Cu" "B.Paste" "B.Mask")
			(roundrect_rratio 0.25)
			(net 23 "+3V3")
			(pintype "passive")
		)
	)
	(footprint "antmicro-footprints:R_0402_1005Metric"
		(layer "B.Cu")
		(at 118.325 112.433751 180)
		(descr "Resistor SMD 0402")
		(tags "resistor SMD 0402")
		(property "Reference" "R12"
			(at -3.255 -0.47725 0)
			(layer "B.SilkS")
			(effects
				(font
					(size 0.7 0.7)
					(thickness 0.15)
				)
				(justify left bottom mirror)
			)
		)
		(property "Value" "R_1k_0402"
			(at -1.011843 -1.772047 0)
			(layer "B.Fab")
			(effects
				(font
					(size 0.7 0.7)
					(thickness 0.15)
				)
				(justify left bottom mirror)
			)
		)
		(property "Footprint" "antmicro-footprints:R_0402_1005Metric"
			(at 0 0 0)
			(layer "B.Fab")
			(hide yes)
			(effects
				(font
					(size 1.27 1.27)
					(thickness 0.15)
				)
				(justify mirror)
			)
		)
		(property "Datasheet" "https://www.bourns.com/docs/product-datasheets/cr.pdf"
			(at 0 0 0)
			(layer "B.Fab")
			(hide yes)
			(effects
				(font
					(size 1.27 1.27)
					(thickness 0.15)
				)
				(justify mirror)
			)
		)
		(property "Description" "SMD Chip Resistor, 1 kohm, ± 1%, 63 mW, 0402 [1005 Metric], Thick Film, General Purpose"
			(at 0 0 0)
			(layer "B.Fab")
			(hide yes)
			(effects
				(font
					(size 1.27 1.27)
					(thickness 0.15)
				)
				(justify mirror)
			)
		)
		(property "MPN" "CR0402-FX-1001GLF"
			(at 0 0 0)
			(unlocked yes)
			(layer "B.Fab")
			(hide yes)
			(effects
				(font
					(size 1 1)
					(thickness 0.15)
				)
				(justify mirror)
			)
		)
		(property "Manufacturer" "Bourns"
			(at 0 0 0)
			(unlocked yes)
			(layer "B.Fab")
			(hide yes)
			(effects
				(font
					(size 1 1)
					(thickness 0.15)
				)
				(justify mirror)
			)
		)
		(property "License" "Apache-2.0"
			(at 0 0 0)
			(unlocked yes)
			(layer "B.Fab")
			(hide yes)
			(effects
				(font
					(size 1 1)
					(thickness 0.15)
				)
				(justify mirror)
			)
		)
		(property "Author" "Antmicro"
			(at 0 0 0)
			(unlocked yes)
			(layer "B.Fab")
			(hide yes)
			(effects
				(font
					(size 1 1)
					(thickness 0.15)
				)
				(justify mirror)
			)
		)
		(property "Val" "1k"
			(at 0 0 0)
			(unlocked yes)
			(layer "B.Fab")
			(hide yes)
			(effects
				(font
					(size 1 1)
					(thickness 0.15)
				)
				(justify mirror)
			)
		)
		(property "Tolerance" "1%"
			(at 0 0 0)
			(unlocked yes)
			(layer "B.Fab")
			(hide yes)
			(effects
				(font
					(size 1 1)
					(thickness 0.15)
				)
				(justify mirror)
			)
		)
		(property "Public" "False"
			(at 0 0 0)
			(unlocked yes)
			(layer "B.Fab")
			(hide yes)
			(effects
				(font
					(size 1 1)
					(thickness 0.15)
				)
				(justify mirror)
			)
		)
		(sheetname "Root")
		(sheetfile "jetson-orin-baseboard-oculink-expansion.kicad_sch")
		(attr smd)
		(fp_rect
			(start -0.925 0.47)
			(end 0.925 -0.47)
			(stroke
				(width 0.05)
				(type default)
			)
			(fill none)
			(layer "B.CrtYd")
		)
		(fp_rect
			(start -0.5 0.25)
			(end 0.5 -0.25)
			(stroke
				(width 0.15)
				(type solid)
			)
			(fill none)
			(layer "B.Fab")
		)
		(fp_text user "Author: Antmicro"
			(at -0.95 -4.169 0)
			(layer "B.Fab")
			(hide yes)
			(effects
				(font
					(size 0.7 0.7)
					(thickness 0.15)
				)
				(justify left bottom mirror)
			)
		)
		(fp_text user "${REFERENCE}"
			(at -0.95 -3.168 0)
			(layer "B.Fab")
			(hide yes)
			(effects
				(font
					(size 0.7 0.7)
					(thickness 0.15)
				)
				(justify left bottom mirror)
			)
		)
		(fp_text user "License: Apache-2.0"
			(at -0.95 -5.169 0)
			(layer "B.Fab")
			(hide yes)
			(effects
				(font
					(size 0.7 0.7)
					(thickness 0.15)
				)
				(justify left bottom mirror)
			)
		)
		(pad "1" smd roundrect
			(at -0.48 0 180)
			(size 0.59 0.64)
			(layers "B.Cu" "B.Paste" "B.Mask")
			(roundrect_rratio 0.25)
			(net 23 "+3V3")
			(pintype "passive")
		)
		(pad "2" smd roundrect
			(at 0.48 0 180)
			(size 0.59 0.64)
			(layers "B.Cu" "B.Paste" "B.Mask")
			(roundrect_rratio 0.25)
			(net 93 "/RX_FG1")
			(pintype "passive")
		)
	)
	(footprint "antmicro-footprints:R_0402_1005Metric"
		(layer "B.Cu")
		(at 127.944 126.66775)
		(descr "Resistor SMD 0402")
		(tags "resistor SMD 0402")
		(property "Reference" "R21"
			(at -3.274 -0.37775 0)
			(layer "B.SilkS")
			(effects
				(font
					(size 0.7 0.7)
					(thickness 0.15)
				)
				(justify right top mirror)
			)
		)
		(property "Value" "R_1k_0402"
			(at -1.011843 -1.772047 0)
			(layer "B.Fab")
			(effects
				(font
					(size 0.7 0.7)
					(thickness 0.15)
				)
				(justify right top mirror)
			)
		)
		(property "Footprint" "antmicro-footprints:R_0402_1005Metric"
			(at 0 0 0)
			(layer "B.Fab")
			(hide yes)
			(effects
				(font
					(size 1.27 1.27)
					(thickness 0.15)
				)
				(justify mirror)
			)
		)
		(property "Datasheet" "https://www.bourns.com/docs/product-datasheets/cr.pdf"
			(at 0 0 0)
			(layer "B.Fab")
			(hide yes)
			(effects
				(font
					(size 1.27 1.27)
					(thickness 0.15)
				)
				(justify mirror)
			)
		)
		(property "Description" "SMD Chip Resistor, 1 kohm, ± 1%, 63 mW, 0402 [1005 Metric], Thick Film, General Purpose"
			(at 0 0 0)
			(layer "B.Fab")
			(hide yes)
			(effects
				(font
					(size 1.27 1.27)
					(thickness 0.15)
				)
				(justify mirror)
			)
		)
		(property "MPN" "CR0402-FX-1001GLF"
			(at 0 0 180)
			(unlocked yes)
			(layer "B.Fab")
			(hide yes)
			(effects
				(font
					(size 1 1)
					(thickness 0.15)
				)
				(justify mirror)
			)
		)
		(property "Manufacturer" "Bourns"
			(at 0 0 180)
			(unlocked yes)
			(layer "B.Fab")
			(hide yes)
			(effects
				(font
					(size 1 1)
					(thickness 0.15)
				)
				(justify mirror)
			)
		)
		(property "License" "Apache-2.0"
			(at 0 0 180)
			(unlocked yes)
			(layer "B.Fab")
			(hide yes)
			(effects
				(font
					(size 1 1)
					(thickness 0.15)
				)
				(justify mirror)
			)
		)
		(property "Author" "Antmicro"
			(at 0 0 180)
			(unlocked yes)
			(layer "B.Fab")
			(hide yes)
			(effects
				(font
					(size 1 1)
					(thickness 0.15)
				)
				(justify mirror)
			)
		)
		(property "Val" "1k"
			(at 0 0 180)
			(unlocked yes)
			(layer "B.Fab")
			(hide yes)
			(effects
				(font
					(size 1 1)
					(thickness 0.15)
				)
				(justify mirror)
			)
		)
		(property "Tolerance" "1%"
			(at 0 0 180)
			(unlocked yes)
			(layer "B.Fab")
			(hide yes)
			(effects
				(font
					(size 1 1)
					(thickness 0.15)
				)
				(justify mirror)
			)
		)
		(property "Public" "False"
			(at 0 0 180)
			(unlocked yes)
			(layer "B.Fab")
			(hide yes)
			(effects
				(font
					(size 1 1)
					(thickness 0.15)
				)
				(justify mirror)
			)
		)
		(sheetname "Root")
		(sheetfile "jetson-orin-baseboard-oculink-expansion.kicad_sch")
		(attr smd)
		(fp_rect
			(start -0.925 0.47)
			(end 0.925 -0.47)
			(stroke
				(width 0.05)
				(type default)
			)
			(fill none)
			(layer "B.CrtYd")
		)
		(fp_rect
			(start -0.5 0.25)
			(end 0.5 -0.25)
			(stroke
				(width 0.15)
				(type solid)
			)
			(fill none)
			(layer "B.Fab")
		)
		(fp_text user "${REFERENCE}"
			(at -0.95 -3.168 0)
			(layer "B.Fab")
			(hide yes)
			(effects
				(font
					(size 0.7 0.7)
					(thickness 0.15)
				)
				(justify right top mirror)
			)
		)
		(fp_text user "Author: Antmicro"
			(at -0.95 -4.169 0)
			(layer "B.Fab")
			(hide yes)
			(effects
				(font
					(size 0.7 0.7)
					(thickness 0.15)
				)
				(justify right top mirror)
			)
		)
		(fp_text user "License: Apache-2.0"
			(at -0.95 -5.169 0)
			(layer "B.Fab")
			(hide yes)
			(effects
				(font
					(size 0.7 0.7)
					(thickness 0.15)
				)
				(justify right top mirror)
			)
		)
		(pad "1" smd roundrect
			(at -0.48 0)
			(size 0.59 0.64)
			(layers "B.Cu" "B.Paste" "B.Mask")
			(roundrect_rratio 0.25)
			(net 23 "+3V3")
			(pintype "passive")
		)
		(pad "2" smd roundrect
			(at 0.48 0)
			(size 0.59 0.64)
			(layers "B.Cu" "B.Paste" "B.Mask")
			(roundrect_rratio 0.25)
			(net 98 "/TX_EQ1")
			(pintype "passive")
		)
	)
	(footprint "antmicro-footprints:R_0402_1005Metric"
		(layer "B.Cu")
		(at 116.475 111.093751)
		(descr "Resistor SMD 0402")
		(tags "resistor SMD 0402")
		(property "Reference" "R11"
			(at -3.251667 -0.383751 0)
			(layer "B.SilkS")
			(effects
				(font
					(size 0.7 0.7)
					(thickness 0.15)
				)
				(justify right top mirror)
			)
		)
		(property "Value" "R_1k_0402"
			(at -1.011843 -1.772047 0)
			(layer "B.Fab")
			(effects
				(font
					(size 0.7 0.7)
					(thickness 0.15)
				)
				(justify right top mirror)
			)
		)
		(property "Footprint" "antmicro-footprints:R_0402_1005Metric"
			(at 0 0 0)
			(layer "B.Fab")
			(hide yes)
			(effects
				(font
					(size 1.27 1.27)
					(thickness 0.15)
				)
				(justify mirror)
			)
		)
		(property "Datasheet" "https://www.bourns.com/docs/product-datasheets/cr.pdf"
			(at 0 0 0)
			(layer "B.Fab")
			(hide yes)
			(effects
				(font
					(size 1.27 1.27)
					(thickness 0.15)
				)
				(justify mirror)
			)
		)
		(property "Description" "SMD Chip Resistor, 1 kohm, ± 1%, 63 mW, 0402 [1005 Metric], Thick Film, General Purpose"
			(at 0 0 0)
			(layer "B.Fab")
			(hide yes)
			(effects
				(font
					(size 1.27 1.27)
					(thickness 0.15)
				)
				(justify mirror)
			)
		)
		(property "MPN" "CR0402-FX-1001GLF"
			(at 0 0 180)
			(unlocked yes)
			(layer "B.Fab")
			(hide yes)
			(effects
				(font
					(size 1 1)
					(thickness 0.15)
				)
				(justify mirror)
			)
		)
		(property "Manufacturer" "Bourns"
			(at 0 0 180)
			(unlocked yes)
			(layer "B.Fab")
			(hide yes)
			(effects
				(font
					(size 1 1)
					(thickness 0.15)
				)
				(justify mirror)
			)
		)
		(property "License" "Apache-2.0"
			(at 0 0 180)
			(unlocked yes)
			(layer "B.Fab")
			(hide yes)
			(effects
				(font
					(size 1 1)
					(thickness 0.15)
				)
				(justify mirror)
			)
		)
		(property "Author" "Antmicro"
			(at 0 0 180)
			(unlocked yes)
			(layer "B.Fab")
			(hide yes)
			(effects
				(font
					(size 1 1)
					(thickness 0.15)
				)
				(justify mirror)
			)
		)
		(property "Val" "1k"
			(at 0 0 180)
			(unlocked yes)
			(layer "B.Fab")
			(hide yes)
			(effects
				(font
					(size 1 1)
					(thickness 0.15)
				)
				(justify mirror)
			)
		)
		(property "Tolerance" "1%"
			(at 0 0 180)
			(unlocked yes)
			(layer "B.Fab")
			(hide yes)
			(effects
				(font
					(size 1 1)
					(thickness 0.15)
				)
				(justify mirror)
			)
		)
		(property "Public" "False"
			(at 0 0 180)
			(unlocked yes)
			(layer "B.Fab")
			(hide yes)
			(effects
				(font
					(size 1 1)
					(thickness 0.15)
				)
				(justify mirror)
			)
		)
		(sheetname "Root")
		(sheetfile "jetson-orin-baseboard-oculink-expansion.kicad_sch")
		(attr smd)
		(fp_rect
			(start -0.925 0.47)
			(end 0.925 -0.47)
			(stroke
				(width 0.05)
				(type default)
			)
			(fill none)
			(layer "B.CrtYd")
		)
		(fp_rect
			(start -0.5 0.25)
			(end 0.5 -0.25)
			(stroke
				(width 0.15)
				(type solid)
			)
			(fill none)
			(layer "B.Fab")
		)
		(fp_text user "${REFERENCE}"
			(at -0.95 -3.168 0)
			(layer "B.Fab")
			(hide yes)
			(effects
				(font
					(size 0.7 0.7)
					(thickness 0.15)
				)
				(justify right top mirror)
			)
		)
		(fp_text user "License: Apache-2.0"
			(at -0.95 -5.169 0)
			(layer "B.Fab")
			(hide yes)
			(effects
				(font
					(size 0.7 0.7)
					(thickness 0.15)
				)
				(justify right top mirror)
			)
		)
		(fp_text user "Author: Antmicro"
			(at -0.95 -4.169 0)
			(layer "B.Fab")
			(hide yes)
			(effects
				(font
					(size 0.7 0.7)
					(thickness 0.15)
				)
				(justify right top mirror)
			)
		)
		(pad "1" smd roundrect
			(at -0.48 0)
			(size 0.59 0.64)
			(layers "B.Cu" "B.Paste" "B.Mask")
			(roundrect_rratio 0.25)
			(net 51 "GND")
			(pintype "passive")
		)
		(pad "2" smd roundrect
			(at 0.48 0)
			(size 0.59 0.64)
			(layers "B.Cu" "B.Paste" "B.Mask")
			(roundrect_rratio 0.25)
			(net 92 "/RX_FG0")
			(pintype "passive")
		)
	)
	(footprint "antmicro-footprints:TP_SMD_1.5mm"
		(layer "B.Cu")
		(at 142.4 131.231062 180)
		(property "Reference" "TP8"
			(at -0.8 -12.588398 180)
			(layer "B.SilkS")
			(hide yes)
			(effects
				(font
					(size 0.7 0.7)
					(thickness 0.15)
				)
				(justify left bottom mirror)
			)
		)
		(property "Value" "TP_1.5mm_SMD"
			(at 1.438222 -0.794949 0)
			(layer "B.Fab")
			(effects
				(font
					(size 0.7 0.7)
					(thickness 0.15)
				)
				(justify left bottom mirror)
			)
		)
		(property "Footprint" "antmicro-footprints:TP_SMD_1.5mm"
			(at 0 0 0)
			(layer "B.Fab")
			(hide yes)
			(effects
				(font
					(size 1.27 1.27)
					(thickness 0.15)
				)
				(justify mirror)
			)
		)
		(property "Description" "test point, SMT"
			(at 0 0 0)
			(layer "B.Fab")
			(hide yes)
			(effects
				(font
					(size 1.27 1.27)
					(thickness 0.15)
				)
				(justify mirror)
			)
		)
		(property "MPN" ""
			(at 0 0 0)
			(unlocked yes)
			(layer "B.Fab")
			(hide yes)
			(effects
				(font
					(size 1 1)
					(thickness 0.15)
				)
				(justify mirror)
			)
		)
		(property "Manufacturer" ""
			(at 0 0 0)
			(unlocked yes)
			(layer "B.Fab")
			(hide yes)
			(effects
				(font
					(size 1 1)
					(thickness 0.15)
				)
				(justify mirror)
			)
		)
		(property "Author" "Antmicro"
			(at 0 0 0)
			(unlocked yes)
			(layer "B.Fab")
			(hide yes)
			(effects
				(font
					(size 1 1)
					(thickness 0.15)
				)
				(justify mirror)
			)
		)
		(property "License" "Apache-2.0"
			(at 0 0 0)
			(unlocked yes)
			(layer "B.Fab")
			(hide yes)
			(effects
				(font
					(size 1 1)
					(thickness 0.15)
				)
				(justify mirror)
			)
		)
		(sheetname "Root")
		(sheetfile "jetson-orin-baseboard-oculink-expansion.kicad_sch")
		(attr exclude_from_pos_files exclude_from_bom)
		(fp_circle
			(center 0 0)
			(end 0.85 0)
			(stroke
				(width 0.05)
				(type default)
			)
			(fill none)
			(layer "B.CrtYd")
		)
		(fp_text user "License: Apache-2.0"
			(at -0.7 -5.301 0)
			(layer "B.Fab")
			(hide yes)
			(effects
				(font
					(size 0.7 0.7)
					(thickness 0.15)
				)
				(justify left bottom mirror)
			)
		)
		(fp_text user "${REFERENCE}"
			(at -0.7 -2.9 0)
			(layer "B.Fab")
			(hide yes)
			(effects
				(font
					(size 0.7 0.7)
					(thickness 0.15)
				)
				(justify left bottom mirror)
			)
		)
		(fp_text user "Author: Antmicro"
			(at -0.7 -4.101 0)
			(layer "B.Fab")
			(hide yes)
			(effects
				(font
					(size 0.7 0.7)
					(thickness 0.15)
				)
				(justify left bottom mirror)
			)
		)
		(pad "1" smd circle
			(at 0 0 270)
			(size 1.5 1.5)
			(layers "B.Cu" "B.Mask")
			(net 23 "+3V3")
			(pinfunction "1")
			(pintype "passive")
		)
	)
)
